(kicad_pcb
	(version 20260206)
	(generator "pcbnew")
	(generator_version "10.0")
	(general
		(thickness 1.6)
		(legacy_teardrops no)
	)
	(paper "A4")
	(title_block
		(title "Wiwynn_Tioga_Pass_MB.brd")
		(comment 1 "Tioga Pass / footprints 1950-1955 of 4770")
	)
	(layers
		(0 "F.Cu" signal "TOP")
		(4 "In1.Cu" signal "L2GND")
		(6 "In2.Cu" signal "L3")
		(8 "In3.Cu" signal "L4GND")
		(10 "In4.Cu" signal "L5")
		(12 "In5.Cu" signal "L6GND")
		(14 "In6.Cu" signal "L7VCC")
		(16 "In7.Cu" signal "L8VCC")
		(18 "In8.Cu" signal "L9GND")
		(20 "In9.Cu" signal "L10")
		(22 "In10.Cu" signal "L11GND")
		(24 "In11.Cu" signal "L12")
		(26 "In12.Cu" signal "L13GND")
		(2 "B.Cu" signal "BOTTOM")
		(9 "F.Adhes" user "F.Adhesive")
		(11 "B.Adhes" user "B.Adhesive")
		(13 "F.Paste" user "Package Geometry/Pastemask Top")
		(15 "B.Paste" user "Package Geometry/Pastemask Bottom")
		(5 "F.SilkS" user "Ref Des/Silkscreen Top")
		(7 "B.SilkS" user "Ref Des/Silkscreen Bottom")
		(1 "F.Mask" user "Board Geometry/Soldermask Top")
		(3 "B.Mask" user "Board Geometry/Soldermask Bottom")
		(17 "Dwgs.User" user "User.Drawings")
		(19 "Cmts.User" user "User.Comments")
		(21 "Eco1.User" user "User.Eco1")
		(23 "Eco2.User" user "User.Eco2")
		(25 "Edge.Cuts" user "Board Geometry/Outline")
		(27 "Margin" user)
		(31 "F.CrtYd" user "Package Geometry/Place Bound Top")
		(29 "B.CrtYd" user "Package Geometry/Place Bound Bottom")
		(35 "F.Fab" user "Ref Des/Assembly Top")
		(33 "B.Fab" user "Ref Des/Assembly Bottom")
	)
	(footprint ""
		(layer "F.Cu")
		(at 5.045456 -17.460976 90)
		(property "Reference" "EU1F1"
			(at 3.789172 1.463294 0)
			(unlocked yes)
			(layer "F.SilkS")
			(effects
				(font
					(size 0.7874 0.5842)
					(thickness 0.1524)
				)
			)
		)
		(property "Value" ""
			(at 0 0 90)
			(layer "F.Fab")
			(effects
				(font
					(size 1.27 1.27)
				)
			)
		)
		(duplicate_pad_numbers_are_jumpers no)
		(fp_line
			(start 2.9718 -3.5052)
			(end 2.9718 3.429)
			(stroke
				(width 0.1524)
				(type default)
			)
			(layer "F.SilkS")
		)
		(fp_line
			(start -3.0099 -3.5052)
			(end 2.9718 -3.5052)
			(stroke
				(width 0.1524)
				(type default)
			)
			(layer "F.SilkS")
		)
		(fp_line
			(start 2.9718 3.429)
			(end -3.0099 3.429)
			(stroke
				(width 0.1524)
				(type default)
			)
			(layer "F.SilkS")
		)
		(fp_line
			(start -3.0099 3.429)
			(end -3.0099 -3.5052)
			(stroke
				(width 0.1524)
				(type default)
			)
			(layer "F.SilkS")
		)
		(fp_circle
			(center -3.057398 -2.678684)
			(end -3.057398 -2.551684)
			(stroke
				(width 0.254)
				(type default)
			)
			(fill no)
			(layer "F.SilkS")
		)
		(fp_poly
			(pts
				(xy -2.9972 -3.4925) (xy -2.9972 -2.6924) (xy -2.1971 -3.4925)
			)
			(stroke
				(width 0)
				(type default)
			)
			(fill yes)
			(layer "F.SilkS")
		)
		(fp_poly
			(pts
				(xy -2.549906 -3.050032) (xy -2.549906 3.050032) (xy 2.549906 3.050032) (xy 2.549906 -3.050032)
			)
			(stroke
				(width 0)
				(type default)
			)
			(fill no)
			(layer "F.CrtYd")
		)
		(fp_line
			(start 2.549906 -3.050032)
			(end 2.549906 3.050032)
			(stroke
				(width 0.1)
				(type default)
			)
			(layer "F.Fab")
		)
		(fp_line
			(start -2.549906 -3.050032)
			(end 2.549906 -3.050032)
			(stroke
				(width 0.1)
				(type default)
			)
			(layer "F.Fab")
		)
		(fp_line
			(start 2.549906 3.050032)
			(end -2.549906 3.050032)
			(stroke
				(width 0.1)
				(type default)
			)
			(layer "F.Fab")
		)
		(fp_line
			(start -2.549906 3.050032)
			(end -2.549906 -3.050032)
			(stroke
				(width 0.1)
				(type default)
			)
			(layer "F.Fab")
		)
		(fp_circle
			(center -3.057398 -2.678684)
			(end -3.057398 -2.551684)
			(stroke
				(width 0.254)
				(type default)
			)
			(fill no)
			(layer "F.Fab")
		)
		(pad "1" smd rect
			(at -2.39522 -2.279904 90)
			(size 0.7112 0.254)
			(layers "F.Cu" "F.Mask" "F.Paste")
			(net "PVDDQ_GHJ")
		)
		(pad "2" smd rect
			(at -2.39522 -1.83007 90)
			(size 0.7112 0.254)
			(layers "F.Cu" "F.Mask" "F.Paste")
			(net "GND")
		)
		(pad "3" smd rect
			(at -2.39522 -1.379982 90)
			(size 0.7112 0.254)
			(layers "F.Cu" "F.Mask" "F.Paste")
			(net "VR_PVDDQ_GHJ_PH2_VCIN")
		)
		(pad "4" smd rect
			(at -2.39522 -0.929894 90)
			(size 0.7112 0.254)
			(layers "F.Cu" "F.Mask" "F.Paste")
			(net "P5V_STBY")
		)
		(pad "5" smd rect
			(at -2.39522 -0.48006 90)
			(size 0.7112 0.254)
			(layers "F.Cu" "F.Mask" "F.Paste")
			(net "GND")
		)
		(pad "6" smd rect
			(at -2.39522 -0.029972 90)
			(size 0.7112 0.254)
			(layers "F.Cu" "F.Mask" "F.Paste")
			(net "TP_PVDDQ_GHJ_PH2_GL_0")
		)
		(pad "7" smd custom
			(at 0.016764 1.145032 90)
			(size 0.53975 0.53975)
			(layers "F.Cu" "F.Mask" "F.Paste")
			(net "GND")
			(options
				(clearance outline)
				(anchor circle)
			)
			(primitives
				(gr_poly
					(pts
						(xy -2.7051 1.0795) (xy -2.7051 -0.3683) (xy -0.9271 -0.3683) (xy -0.9271 -1.0795) (xy 2.7051 -1.0795)
						(xy 2.7051 1.0795)
					)
					(width 0)
					(fill yes)
				)
			)
		)
		(pad "10" smd rect
			(at -0.008382 2.874772 90)
			(size 4.3434 0.6096)
			(layers "F.Cu" "F.Mask" "F.Paste")
			(net "VR_PVDDQ_GHJ_PH2_SW")
		)
		(pad "25" smd rect
			(at 1.548384 -1.283208 90)
			(size 2.3368 2.0066)
			(layers "F.Cu" "F.Mask" "F.Paste")
			(net "VR_FET_SW_P12V_STBY_PVDDQ_GHJ")
		)
		(pad "30" smd rect
			(at 2.050034 -2.895092 90)
			(size 0.254 0.7112)
			(layers "F.Cu" "F.Mask" "F.Paste")
			(net "VR_FET_SW_P12V_STBY_PVDDQ_GHJ")
		)
		(pad "31" smd rect
			(at 1.599946 -2.895092 90)
			(size 0.254 0.7112)
			(layers "F.Cu" "F.Mask" "F.Paste")
			(net "Net_297")
		)
		(pad "32" smd rect
			(at 1.150112 -2.895092 90)
			(size 0.254 0.7112)
			(layers "F.Cu" "F.Mask" "F.Paste")
			(net "VR_PVDDQ_GHJ_PH2_PHASE")
		)
		(pad "33" smd rect
			(at 0.700024 -2.895092 90)
			(size 0.254 0.7112)
			(layers "F.Cu" "F.Mask" "F.Paste")
			(net "VR_PVDDQ_GHJ_PH2_BOOT_R")
		)
		(pad "34" smd rect
			(at 0.249936 -2.895092 90)
			(size 0.254 0.7112)
			(layers "F.Cu" "F.Mask" "F.Paste")
			(net "VR_PVDDQ_GHJ_PWM2")
		)
		(pad "35" smd rect
			(at -0.199898 -2.895092 90)
			(size 0.254 0.7112)
			(layers "F.Cu" "F.Mask" "F.Paste")
			(net "P5V_STBY")
		)
		(pad "36" smd rect
			(at -0.649986 -2.895092 90)
			(size 0.254 0.7112)
			(layers "F.Cu" "F.Mask" "F.Paste")
			(net "A_TSENSE_PVDDQ_GHJ")
		)
		(pad "37" smd rect
			(at -1.100074 -2.895092 90)
			(size 0.254 0.7112)
			(layers "F.Cu" "F.Mask" "F.Paste")
			(net "VR_PVDDQ_GHJ_PH2_OCSET")
		)
		(pad "38" smd rect
			(at -1.549908 -2.895092 90)
			(size 0.254 0.7112)
			(layers "F.Cu" "F.Mask" "F.Paste")
			(net "ISENSE_PVDDQ_GHJ_PH2_IMON")
		)
		(pad "39" smd rect
			(at -1.999996 -2.895092 90)
			(size 0.254 0.7112)
			(layers "F.Cu" "F.Mask" "F.Paste")
			(net "VR_PVDDQ_GHJ_AIREF2")
		)
		(pad "40" smd rect
			(at -0.871728 -1.283208 90)
			(size 1.8034 2.0066)
			(layers "F.Cu" "F.Mask" "F.Paste")
			(net "GND")
		)
		(pad "41" smd rect
			(at -1.533906 0.247904 90)
			(size 0.508 0.3556)
			(layers "F.Cu" "F.Mask" "F.Paste")
			(net "TP_PVDDQ_GHJ_PH2_GL_1")
		)
	)
	(footprint ""
		(layer "F.Cu")
		(at 21.336 -81.79308)
		(property "Reference" "C1D9"
			(at 0 0 0)
			(layer "F.SilkS")
			(hide yes)
			(effects
				(font
					(size 1.27 1.27)
				)
			)
		)
		(property "Value" ""
			(at 0 0 0)
			(layer "F.Fab")
			(effects
				(font
					(size 1.27 1.27)
				)
			)
		)
		(duplicate_pad_numbers_are_jumpers no)
		(fp_poly
			(pts
				(xy 0.3048 -0.1016) (xy 0.3048 0.9906) (xy -0.3048 0.9906) (xy -0.3048 -0.1016)
			)
			(stroke
				(width 0)
				(type default)
			)
			(fill no)
			(layer "F.CrtYd")
		)
		(fp_line
			(start -0.3048 -0.1016)
			(end -0.3048 0.9906)
			(stroke
				(width 0.1)
				(type default)
			)
			(layer "F.Fab")
		)
		(fp_line
			(start -0.3048 0.9906)
			(end 0.3048 0.9906)
			(stroke
				(width 0.1)
				(type default)
			)
			(layer "F.Fab")
		)
		(fp_line
			(start 0.3048 -0.1016)
			(end -0.3048 -0.1016)
			(stroke
				(width 0.1)
				(type default)
			)
			(layer "F.Fab")
		)
		(fp_line
			(start 0.3048 0.9906)
			(end 0.3048 -0.1016)
			(stroke
				(width 0.1)
				(type default)
			)
			(layer "F.Fab")
		)
		(pad "1" smd rect
			(at 0 0)
			(size 0.508 0.508)
			(layers "F.Cu" "F.Mask" "F.Paste")
			(net "P12V_STBY")
		)
		(pad "2" smd rect
			(at 0 0.889)
			(size 0.508 0.508)
			(layers "F.Cu" "F.Mask" "F.Paste")
			(net "AGND_HSC")
		)
		(zone
			(layer "F.Cu")
			(hatch none 0.5)
			(connect_pads
				(clearance 0)
			)
			(min_thickness 0.25)
			(keepout
				(tracks allowed)
				(vias not_allowed)
				(pads allowed)
				(copperpour not_allowed)
				(footprints allowed)
			)
			(placement
				(enabled no)
				(sheetname "")
			)
			(fill
				(thermal_gap 0.5)
				(thermal_bridge_width 0.5)
				(island_removal_mode 0)
			)
			(polygon
				(pts
					(xy 21.082 -81.53908) (xy 21.59 -81.53908) (xy 21.59 -81.15808) (xy 21.082 -81.15808)
				)
			)
		)
		(zone
			(layer "F.Cu")
			(hatch none 0.5)
			(connect_pads
				(clearance 0)
			)
			(min_thickness 0.25)
			(keepout
				(tracks not_allowed)
				(vias allowed)
				(pads allowed)
				(copperpour not_allowed)
				(footprints allowed)
			)
			(placement
				(enabled no)
				(sheetname "")
			)
			(fill
				(thermal_gap 0.5)
				(thermal_bridge_width 0.5)
				(island_removal_mode 0)
			)
			(polygon
				(pts
					(xy 21.082 -81.15808) (xy 21.59 -81.15808) (xy 21.59 -81.53908) (xy 21.082 -81.53908)
				)
			)
		)
	)
	(footprint ""
		(layer "F.Cu")
		(at 198.039228 -93.861382 90)
		(property "Reference" "C4C5"
			(at 0 0 90)
			(layer "F.SilkS")
			(hide yes)
			(effects
				(font
					(size 1.27 1.27)
				)
			)
		)
		(property "Value" ""
			(at 0 0 90)
			(layer "F.Fab")
			(effects
				(font
					(size 1.27 1.27)
				)
			)
		)
		(duplicate_pad_numbers_are_jumpers no)
		(fp_rect
			(start 0.3048 0.9906)
			(end -0.3048 -0.1016)
			(stroke
				(width 0)
				(type default)
			)
			(fill no)
			(layer "F.CrtYd")
		)
		(fp_line
			(start 0.3048 -0.1016)
			(end -0.3048 -0.1016)
			(stroke
				(width 0.1)
				(type default)
			)
			(layer "F.Fab")
		)
		(fp_line
			(start -0.3048 -0.1016)
			(end -0.3048 0.9906)
			(stroke
				(width 0.1)
				(type default)
			)
			(layer "F.Fab")
		)
		(fp_line
			(start 0.3048 0.9906)
			(end 0.3048 -0.1016)
			(stroke
				(width 0.1)
				(type default)
			)
			(layer "F.Fab")
		)
		(fp_line
			(start -0.3048 0.9906)
			(end 0.3048 0.9906)
			(stroke
				(width 0.1)
				(type default)
			)
			(layer "F.Fab")
		)
		(pad "1" smd rect
			(at 0 0 90)
			(size 0.508 0.508)
			(layers "F.Cu" "F.Mask" "F.Paste")
			(net "P5V_STBY")
		)
		(pad "2" smd rect
			(at 0 0.889 90)
			(size 0.508 0.508)
			(layers "F.Cu" "F.Mask" "F.Paste")
			(net "GND")
		)
		(zone
			(layer "F.Cu")
			(hatch none 0.5)
			(connect_pads
				(clearance 0)
			)
			(min_thickness 0.25)
			(keepout
				(tracks not_allowed)
				(vias allowed)
				(pads allowed)
				(copperpour not_allowed)
				(footprints allowed)
			)
			(placement
				(enabled no)
				(sheetname "")
			)
			(fill
				(thermal_gap 0.5)
				(thermal_bridge_width 0.5)
				(island_removal_mode 0)
			)
			(polygon
				(pts
					(xy 198.674228 -94.115382) (xy 198.293228 -94.115382) (xy 198.293228 -93.607382) (xy 198.674228 -93.607382)
				)
			)
		)
		(zone
			(layer "F.Cu")
			(hatch none 0.5)
			(connect_pads
				(clearance 0)
			)
			(min_thickness 0.25)
			(keepout
				(tracks allowed)
				(vias not_allowed)
				(pads allowed)
				(copperpour not_allowed)
				(footprints allowed)
			)
			(placement
				(enabled no)
				(sheetname "")
			)
			(fill
				(thermal_gap 0.5)
				(thermal_bridge_width 0.5)
				(island_removal_mode 0)
			)
			(polygon
				(pts
					(xy 198.674228 -94.115382) (xy 198.293228 -94.115382) (xy 198.293228 -93.607382) (xy 198.674228 -93.607382)
				)
			)
		)
	)
	(footprint ""
		(layer "F.Cu")
		(at 406.197054 -64.298068)
		(property "Reference" "R8E2"
			(at 0 0 0)
			(layer "F.SilkS")
			(hide yes)
			(effects
				(font
					(size 1.27 1.27)
				)
			)
		)
		(property "Value" ""
			(at 0 0 0)
			(layer "F.Fab")
			(effects
				(font
					(size 1.27 1.27)
				)
			)
		)
		(duplicate_pad_numbers_are_jumpers no)
		(fp_poly
			(pts
				(xy -0.2794 -0.1016) (xy 0.2794 -0.1016) (xy 0.2794 0.9906) (xy -0.2794 0.9906)
			)
			(stroke
				(width 0)
				(type default)
			)
			(fill no)
			(layer "F.CrtYd")
		)
		(fp_line
			(start -0.2794 -0.1016)
			(end -0.2794 0.9906)
			(stroke
				(width 0.1)
				(type default)
			)
			(layer "F.Fab")
		)
		(fp_line
			(start -0.2794 0.9906)
			(end 0.2794 0.9906)
			(stroke
				(width 0.1)
				(type default)
			)
			(layer "F.Fab")
		)
		(fp_line
			(start 0.2794 -0.1016)
			(end -0.2794 -0.1016)
			(stroke
				(width 0.1)
				(type default)
			)
			(layer "F.Fab")
		)
		(fp_line
			(start 0.2794 0.9906)
			(end 0.2794 -0.1016)
			(stroke
				(width 0.1)
				(type default)
			)
			(layer "F.Fab")
		)
		(pad "1" smd rect
			(at 0 0)
			(size 0.508 0.508)
			(layers "F.Cu" "F.Mask" "F.Paste")
			(net "XDP_SPI_PCH_MOSI_BOOT_HALT_N")
		)
		(pad "2" smd rect
			(at 0 0.889)
			(size 0.508 0.508)
			(layers "F.Cu" "F.Mask" "F.Paste")
			(net "SPI_PCH_MOSI")
		)
		(zone
			(layer "F.Cu")
			(hatch none 0.5)
			(connect_pads
				(clearance 0)
			)
			(min_thickness 0.25)
			(keepout
				(tracks allowed)
				(vias not_allowed)
				(pads allowed)
				(copperpour not_allowed)
				(footprints allowed)
			)
			(placement
				(enabled no)
				(sheetname "")
			)
			(fill
				(thermal_gap 0.5)
				(thermal_bridge_width 0.5)
				(island_removal_mode 0)
			)
			(polygon
				(pts
					(xy 405.943054 -64.044068) (xy 406.451054 -64.044068) (xy 406.451054 -63.663068) (xy 405.943054 -63.663068)
				)
			)
		)
		(zone
			(layer "F.Cu")
			(hatch none 0.5)
			(connect_pads
				(clearance 0)
			)
			(min_thickness 0.25)
			(keepout
				(tracks not_allowed)
				(vias allowed)
				(pads allowed)
				(copperpour not_allowed)
				(footprints allowed)
			)
			(placement
				(enabled no)
				(sheetname "")
			)
			(fill
				(thermal_gap 0.5)
				(thermal_bridge_width 0.5)
				(island_removal_mode 0)
			)
			(polygon
				(pts
					(xy 405.943054 -63.663068) (xy 406.451054 -63.663068) (xy 406.451054 -64.044068) (xy 405.943054 -64.044068)
				)
			)
		)
	)
	(footprint ""
		(layer "F.Cu")
		(at 28.380182 -130.5814 -90)
		(property "Reference" "C1B7"
			(at 0 0 270)
			(layer "F.SilkS")
			(hide yes)
			(effects
				(font
					(size 1.27 1.27)
				)
			)
		)
		(property "Value" ""
			(at 0 0 270)
			(layer "F.Fab")
			(effects
				(font
					(size 1.27 1.27)
				)
			)
		)
		(duplicate_pad_numbers_are_jumpers no)
		(fp_poly
			(pts
				(xy -0.7239 -0.2159) (xy 0.7239 -0.2159) (xy 0.7239 1.9939) (xy -0.7239 1.9939)
			)
			(stroke
				(width 0)
				(type default)
			)
			(fill no)
			(layer "F.CrtYd")
		)
		(fp_line
			(start -0.7239 1.9939)
			(end 0.7239 1.9939)
			(stroke
				(width 0.1)
				(type default)
			)
			(layer "F.Fab")
		)
		(fp_line
			(start 0.7239 1.9939)
			(end 0.7239 -0.2159)
			(stroke
				(width 0.1)
				(type default)
			)
			(layer "F.Fab")
		)
		(fp_line
			(start -0.7239 -0.2159)
			(end -0.7239 1.9939)
			(stroke
				(width 0.1)
				(type default)
			)
			(layer "F.Fab")
		)
		(fp_line
			(start 0.7239 -0.2159)
			(end -0.7239 -0.2159)
			(stroke
				(width 0.1)
				(type default)
			)
			(layer "F.Fab")
		)
		(pad "1" smd rect
			(at 0 0 270)
			(size 1.27 1.016)
			(layers "F.Cu" "F.Mask" "F.Paste")
			(net "P12V_NVDIMM_KLM")
		)
		(pad "2" smd rect
			(at 0 1.778 270)
			(size 1.27 1.016)
			(layers "F.Cu" "F.Mask" "F.Paste")
			(net "GND")
		)
		(zone
			(layer "F.Cu")
			(hatch none 0.5)
			(connect_pads
				(clearance 0)
			)
			(min_thickness 0.25)
			(keepout
				(tracks not_allowed)
				(vias allowed)
				(pads allowed)
				(copperpour not_allowed)
				(footprints allowed)
			)
			(placement
				(enabled no)
				(sheetname "")
			)
			(fill
				(thermal_gap 0.5)
				(thermal_bridge_width 0.5)
				(island_removal_mode 0)
			)
			(polygon
				(pts
					(xy 27.872182 -131.2164) (xy 27.872182 -129.9464) (xy 27.110182 -129.9464) (xy 27.110182 -131.2164)
				)
			)
		)
	)
	(footprint ""
		(layer "F.Cu")
		(at 338.836 -16.383 -90)
		(property "Reference" "R7G2"
			(at 0 0 270)
			(layer "F.SilkS")
			(hide yes)
			(effects
				(font
					(size 1.27 1.27)
				)
			)
		)
		(property "Value" ""
			(at 0 0 270)
			(layer "F.Fab")
			(effects
				(font
					(size 1.27 1.27)
				)
			)
		)
		(duplicate_pad_numbers_are_jumpers no)
		(fp_rect
			(start 0.2794 0.9906)
			(end -0.2794 -0.1016)
			(stroke
				(width 0)
				(type default)
			)
			(fill no)
			(layer "F.CrtYd")
		)
		(fp_line
			(start -0.2794 0.9906)
			(end 0.2794 0.9906)
			(stroke
				(width 0.1)
				(type default)
			)
			(layer "F.Fab")
		)
		(fp_line
			(start 0.2794 0.9906)
			(end 0.2794 -0.1016)
			(stroke
				(width 0.1)
				(type default)
			)
			(layer "F.Fab")
		)
		(fp_line
			(start -0.2794 -0.1016)
			(end -0.2794 0.9906)
			(stroke
				(width 0.1)
				(type default)
			)
			(layer "F.Fab")
		)
		(fp_line
			(start 0.2794 -0.1016)
			(end -0.2794 -0.1016)
			(stroke
				(width 0.1)
				(type default)
			)
			(layer "F.Fab")
		)
		(pad "1" smd rect
			(at 0 0 270)
			(size 0.508 0.508)
			(layers "F.Cu" "F.Mask" "F.Paste")
			(net "SVID_VDIO_PVDDQ_ABC")
		)
		(pad "2" smd rect
			(at 0 0.889 270)
			(size 0.508 0.508)
			(layers "F.Cu" "F.Mask" "F.Paste")
			(net "SVID_DIO1_CPU0_R")
		)
		(zone
			(layer "F.Cu")
			(hatch none 0.5)
			(connect_pads
				(clearance 0)
			)
			(min_thickness 0.25)
			(keepout
				(tracks not_allowed)
				(vias allowed)
				(pads allowed)
				(copperpour not_allowed)
				(footprints allowed)
			)
			(placement
				(enabled no)
				(sheetname "")
			)
			(fill
				(thermal_gap 0.5)
				(thermal_bridge_width 0.5)
				(island_removal_mode 0)
			)
			(polygon
				(pts
					(xy 338.201 -16.129) (xy 338.582 -16.129) (xy 338.582 -16.637) (xy 338.201 -16.637)
				)
			)
		)
		(zone
			(layer "F.Cu")
			(hatch none 0.5)
			(connect_pads
				(clearance 0)
			)
			(min_thickness 0.25)
			(keepout
				(tracks allowed)
				(vias not_allowed)
				(pads allowed)
				(copperpour not_allowed)
				(footprints allowed)
			)
			(placement
				(enabled no)
				(sheetname "")
			)
			(fill
				(thermal_gap 0.5)
				(thermal_bridge_width 0.5)
				(island_removal_mode 0)
			)
			(polygon
				(pts
					(xy 338.201 -16.129) (xy 338.582 -16.129) (xy 338.582 -16.637) (xy 338.201 -16.637)
				)
			)
		)
	)
)
